(kicad_pcb
	(version 20260206)
	(generator "pcbnew")
	(generator_version "10.0")
	(general
		(thickness 1.6)
		(legacy_teardrops no)
	)
	(paper "A4")
	(title_block
		(title "01162023_DA0F0TEBIF0_F0T_Expander_BD_F_brd_V02_OCP.brd")
		(comment 1 "Grand Teton / footprints 9722-9728 of 9728")
	)
	(layers
		(0 "F.Cu" signal "TOP")
		(4 "In1.Cu" signal "GND")
		(6 "In2.Cu" signal "VCC")
		(8 "In3.Cu" signal "VCC1")
		(10 "In4.Cu" signal "GND1")
		(12 "In5.Cu" signal "IN1")
		(14 "In6.Cu" signal "GND2")
		(16 "In7.Cu" signal "IN2")
		(18 "In8.Cu" signal "GND3")
		(20 "In9.Cu" signal "IN3")
		(22 "In10.Cu" signal "GND4")
		(24 "In11.Cu" signal "IN4")
		(26 "In12.Cu" signal "GND5")
		(28 "In13.Cu" signal "IN5")
		(30 "In14.Cu" signal "GND6")
		(32 "In15.Cu" signal "IN6")
		(34 "In16.Cu" signal "GND7")
		(2 "B.Cu" signal "BOTTOM")
		(9 "F.Adhes" user "F.Adhesive")
		(11 "B.Adhes" user "B.Adhesive")
		(13 "F.Paste" user "Package Geometry/Pastemask Top")
		(15 "B.Paste" user "Package Geometry/Pastemask Bottom")
		(5 "F.SilkS" user "Ref Des/Silkscreen Top")
		(7 "B.SilkS" user "Ref Des/Silkscreen Bottom")
		(1 "F.Mask" user "Board Geometry/Soldermask Top")
		(3 "B.Mask" user "Board Geometry/Soldermask Bottom")
		(17 "Dwgs.User" user "User.Drawings")
		(19 "Cmts.User" user "User.Comments")
		(21 "Eco1.User" user "User.Eco1")
		(23 "Eco2.User" user "User.Eco2")
		(25 "Edge.Cuts" user "Board Geometry/Outline")
		(27 "Margin" user)
		(31 "F.CrtYd" user "Package Geometry/Place Bound Top")
		(29 "B.CrtYd" user "Package Geometry/Place Bound Bottom")
		(35 "F.Fab" user "Ref Des/Assembly Top")
		(33 "B.Fab" user "Ref Des/Assembly Bottom")
	)
	(footprint ""
		(layer "B.Cu")
		(at 339.694012 -218.787218 90)
		(property "Reference" "C2081"
			(at 0 0 90)
			(layer "B.SilkS")
			(hide yes)
			(effects
				(font
					(size 1.27 1.27)
				)
				(justify mirror)
			)
		)
		(property "Value" ""
			(at 0 0 90)
			(layer "B.Fab")
			(effects
				(font
					(size 1.27 1.27)
				)
				(justify mirror)
			)
		)
		(duplicate_pad_numbers_are_jumpers no)
		(fp_line
			(start 0.69215 -0.2921)
			(end -0.69215 -0.2921)
			(stroke
				(width 0.1524)
				(type default)
			)
			(layer "B.SilkS")
		)
		(fp_line
			(start -0.69215 -0.2921)
			(end -0.69215 0.2921)
			(stroke
				(width 0.1524)
				(type default)
			)
			(layer "B.SilkS")
		)
		(fp_line
			(start 0.69215 0.2921)
			(end 0.69215 -0.2921)
			(stroke
				(width 0.1524)
				(type default)
			)
			(layer "B.SilkS")
		)
		(fp_line
			(start -0.69215 0.2921)
			(end 0.69215 0.2921)
			(stroke
				(width 0.1524)
				(type default)
			)
			(layer "B.SilkS")
		)
		(fp_line
			(start 0.51435 -0.2794)
			(end -0.51435 -0.2794)
			(stroke
				(width 0.1)
				(type default)
			)
			(layer "B.Fab")
		)
		(fp_line
			(start -0.51435 -0.2794)
			(end -0.51435 0.2794)
			(stroke
				(width 0.1)
				(type default)
			)
			(layer "B.Fab")
		)
		(fp_line
			(start 0.51435 0.2794)
			(end 0.51435 -0.2794)
			(stroke
				(width 0.1)
				(type default)
			)
			(layer "B.Fab")
		)
		(fp_line
			(start -0.51435 0.2794)
			(end 0.51435 0.2794)
			(stroke
				(width 0.1)
				(type default)
			)
			(layer "B.Fab")
		)
		(pad "1" smd circle
			(at 0.40005 0 270)
			(size 0 0)
			(layers "B.Cu" "B.Mask" "B.Paste")
			(net "P3V3_FPGA_VCCIO4")
		)
		(pad "2" smd circle
			(at -0.40005 0 270)
			(size 0 0)
			(layers "B.Cu" "B.Mask" "B.Paste")
			(net "GND")
		)
		(zone
			(layer "B.Cu")
			(hatch none 0.5)
			(connect_pads
				(clearance 0)
			)
			(min_thickness 0.25)
			(keepout
				(tracks not_allowed)
				(vias allowed)
				(pads allowed)
				(copperpour not_allowed)
				(footprints allowed)
			)
			(placement
				(enabled no)
				(sheetname "")
			)
			(fill
				(thermal_gap 0.5)
				(thermal_bridge_width 0.5)
				(island_removal_mode 0)
			)
			(polygon
				(pts
					(xy 339.781642 -218.977718) (xy 339.839808 -218.886278) (xy 339.839808 -218.686888) (xy 339.781642 -218.596718)
					(xy 339.606382 -218.596718) (xy 339.547962 -218.686888) (xy 339.547962 -218.886278) (xy 339.606128 -218.977718)
				)
			)
		)
	)
	(footprint ""
		(layer "B.Cu")
		(at 203.414376 -371.088666 180)
		(property "Reference" "R6248"
			(at 0 0 0)
			(layer "B.SilkS")
			(hide yes)
			(effects
				(font
					(size 1.27 1.27)
				)
				(justify mirror)
			)
		)
		(property "Value" ""
			(at 0 0 0)
			(layer "B.Fab")
			(effects
				(font
					(size 1.27 1.27)
				)
				(justify mirror)
			)
		)
		(duplicate_pad_numbers_are_jumpers no)
		(fp_line
			(start 0.7874 0.4064)
			(end 0.7874 -0.4064)
			(stroke
				(width 0.1524)
				(type default)
			)
			(layer "B.SilkS")
		)
		(fp_line
			(start 0.7874 -0.4064)
			(end -0.7874 -0.4064)
			(stroke
				(width 0.1524)
				(type default)
			)
			(layer "B.SilkS")
		)
		(fp_line
			(start -0.7874 0.4064)
			(end 0.7874 0.4064)
			(stroke
				(width 0.1524)
				(type default)
			)
			(layer "B.SilkS")
		)
		(fp_line
			(start -0.7874 -0.4064)
			(end -0.7874 0.4064)
			(stroke
				(width 0.1524)
				(type default)
			)
			(layer "B.SilkS")
		)
		(fp_line
			(start 0.67945 0.3048)
			(end 0.67945 -0.305054)
			(stroke
				(width 0.1)
				(type default)
			)
			(layer "B.Fab")
		)
		(fp_line
			(start 0.67945 -0.305054)
			(end 0.12065 -0.305054)
			(stroke
				(width 0.1)
				(type default)
			)
			(layer "B.Fab")
		)
		(fp_line
			(start 0.12065 0.3048)
			(end 0.67945 0.3048)
			(stroke
				(width 0.1)
				(type default)
			)
			(layer "B.Fab")
		)
		(fp_line
			(start 0.12065 0.2794)
			(end 0.12065 0.3048)
			(stroke
				(width 0.1)
				(type default)
			)
			(layer "B.Fab")
		)
		(fp_line
			(start 0.12065 -0.2794)
			(end -0.12065 -0.2794)
			(stroke
				(width 0.1)
				(type default)
			)
			(layer "B.Fab")
		)
		(fp_line
			(start 0.12065 -0.305054)
			(end 0.12065 -0.2794)
			(stroke
				(width 0.1)
				(type default)
			)
			(layer "B.Fab")
		)
		(fp_line
			(start -0.120396 0.3048)
			(end -0.120396 0.2794)
			(stroke
				(width 0.1)
				(type default)
			)
			(layer "B.Fab")
		)
		(fp_line
			(start -0.120396 0.2794)
			(end 0.12065 0.2794)
			(stroke
				(width 0.1)
				(type default)
			)
			(layer "B.Fab")
		)
		(fp_line
			(start -0.12065 -0.2794)
			(end -0.12065 -0.3048)
			(stroke
				(width 0.1)
				(type default)
			)
			(layer "B.Fab")
		)
		(fp_line
			(start -0.12065 -0.3048)
			(end -0.67945 -0.3048)
			(stroke
				(width 0.1)
				(type default)
			)
			(layer "B.Fab")
		)
		(fp_line
			(start -0.67945 0.3048)
			(end -0.120396 0.3048)
			(stroke
				(width 0.1)
				(type default)
			)
			(layer "B.Fab")
		)
		(fp_line
			(start -0.67945 -0.3048)
			(end -0.67945 0.3048)
			(stroke
				(width 0.1)
				(type default)
			)
			(layer "B.Fab")
		)
		(pad "1" smd circle
			(at 0.40005 0)
			(size 0 0)
			(layers "B.Cu" "B.Mask" "B.Paste")
			(net "HSC_ALERT1_R_N")
		)
		(pad "2" smd circle
			(at -0.40005 0)
			(size 0 0)
			(layers "B.Cu" "B.Mask" "B.Paste")
			(net "HSC_ALERT1_N")
		)
	)
	(footprint ""
		(layer "B.Cu")
		(at 293.921942 -296.3926)
		(property "Reference" "C1635"
			(at 0 0 0)
			(layer "B.SilkS")
			(hide yes)
			(effects
				(font
					(size 1.27 1.27)
				)
				(justify mirror)
			)
		)
		(property "Value" ""
			(at 0 0 0)
			(layer "B.Fab")
			(effects
				(font
					(size 1.27 1.27)
				)
				(justify mirror)
			)
		)
		(duplicate_pad_numbers_are_jumpers no)
		(fp_line
			(start -0.299974 -0.150114)
			(end -0.299974 0.150114)
			(stroke
				(width 0.1)
				(type default)
			)
			(layer "B.Fab")
		)
		(fp_line
			(start -0.299974 0.150114)
			(end 0.299974 0.150114)
			(stroke
				(width 0.1)
				(type default)
			)
			(layer "B.Fab")
		)
		(fp_line
			(start 0.299974 -0.150114)
			(end -0.299974 -0.150114)
			(stroke
				(width 0.1)
				(type default)
			)
			(layer "B.Fab")
		)
		(fp_line
			(start 0.299974 0.150114)
			(end 0.299974 -0.150114)
			(stroke
				(width 0.1)
				(type default)
			)
			(layer "B.Fab")
		)
		(pad "1" smd rect
			(at 0.2667 0 180)
			(size 0.3048 0.381)
			(layers "B.Cu" "B.Mask" "B.Paste")
			(net "P0V8_PEX2")
		)
		(pad "2" smd rect
			(at -0.2667 0 180)
			(size 0.3048 0.381)
			(layers "B.Cu" "B.Mask" "B.Paste")
			(net "GND")
		)
	)
	(footprint ""
		(layer "B.Cu")
		(at 65.824862 -293.99992 -90)
		(property "Reference" "C1120"
			(at 0 0 90)
			(layer "B.SilkS")
			(hide yes)
			(effects
				(font
					(size 1.27 1.27)
				)
				(justify mirror)
			)
		)
		(property "Value" ""
			(at 0 0 90)
			(layer "B.Fab")
			(effects
				(font
					(size 1.27 1.27)
				)
				(justify mirror)
			)
		)
		(duplicate_pad_numbers_are_jumpers no)
		(fp_line
			(start -0.299974 0.150114)
			(end 0.299974 0.150114)
			(stroke
				(width 0.1)
				(type default)
			)
			(layer "B.Fab")
		)
		(fp_line
			(start 0.299974 0.150114)
			(end 0.299974 -0.150114)
			(stroke
				(width 0.1)
				(type default)
			)
			(layer "B.Fab")
		)
		(fp_line
			(start -0.299974 -0.150114)
			(end -0.299974 0.150114)
			(stroke
				(width 0.1)
				(type default)
			)
			(layer "B.Fab")
		)
		(fp_line
			(start 0.299974 -0.150114)
			(end -0.299974 -0.150114)
			(stroke
				(width 0.1)
				(type default)
			)
			(layer "B.Fab")
		)
		(pad "1" smd rect
			(at 0.2667 0 90)
			(size 0.3048 0.381)
			(layers "B.Cu" "B.Mask" "B.Paste")
			(net "P0V8_PEX0")
		)
		(pad "2" smd rect
			(at -0.2667 0 90)
			(size 0.3048 0.381)
			(layers "B.Cu" "B.Mask" "B.Paste")
			(net "GND")
		)
	)
	(footprint ""
		(layer "B.Cu")
		(at 165.249098 -301.0154 180)
		(property "Reference" "C1365"
			(at 0 0 0)
			(layer "B.SilkS")
			(hide yes)
			(effects
				(font
					(size 1.27 1.27)
				)
				(justify mirror)
			)
		)
		(property "Value" ""
			(at 0 0 0)
			(layer "B.Fab")
			(effects
				(font
					(size 1.27 1.27)
				)
				(justify mirror)
			)
		)
		(duplicate_pad_numbers_are_jumpers no)
		(fp_line
			(start 0.299974 0.150114)
			(end 0.299974 -0.150114)
			(stroke
				(width 0.1)
				(type default)
			)
			(layer "B.Fab")
		)
		(fp_line
			(start 0.299974 -0.150114)
			(end -0.299974 -0.150114)
			(stroke
				(width 0.1)
				(type default)
			)
			(layer "B.Fab")
		)
		(fp_line
			(start -0.299974 0.150114)
			(end 0.299974 0.150114)
			(stroke
				(width 0.1)
				(type default)
			)
			(layer "B.Fab")
		)
		(fp_line
			(start -0.299974 -0.150114)
			(end -0.299974 0.150114)
			(stroke
				(width 0.1)
				(type default)
			)
			(layer "B.Fab")
		)
		(pad "1" smd rect
			(at 0.2667 0)
			(size 0.3048 0.381)
			(layers "B.Cu" "B.Mask" "B.Paste")
			(net "P0V8_PEX1")
		)
		(pad "2" smd rect
			(at -0.2667 0)
			(size 0.3048 0.381)
			(layers "B.Cu" "B.Mask" "B.Paste")
			(net "GND")
		)
	)
	(footprint ""
		(layer "B.Cu")
		(at 367.258854 -308.685184 90)
		(property "Reference" "C4362"
			(at 0 0 90)
			(layer "B.SilkS")
			(hide yes)
			(effects
				(font
					(size 1.27 1.27)
				)
				(justify mirror)
			)
		)
		(property "Value" ""
			(at 0 0 90)
			(layer "B.Fab")
			(effects
				(font
					(size 1.27 1.27)
				)
				(justify mirror)
			)
		)
		(duplicate_pad_numbers_are_jumpers no)
		(fp_line
			(start 0.299974 -0.150114)
			(end -0.299974 -0.150114)
			(stroke
				(width 0.1)
				(type default)
			)
			(layer "B.Fab")
		)
		(fp_line
			(start -0.299974 -0.150114)
			(end -0.299974 0.150114)
			(stroke
				(width 0.1)
				(type default)
			)
			(layer "B.Fab")
		)
		(fp_line
			(start 0.299974 0.150114)
			(end 0.299974 -0.150114)
			(stroke
				(width 0.1)
				(type default)
			)
			(layer "B.Fab")
		)
		(fp_line
			(start -0.299974 0.150114)
			(end 0.299974 0.150114)
			(stroke
				(width 0.1)
				(type default)
			)
			(layer "B.Fab")
		)
		(pad "1" smd rect
			(at 0.2667 0 270)
			(size 0.3048 0.381)
			(layers "B.Cu" "B.Mask" "B.Paste")
			(net "P0V8_PEX3")
		)
		(pad "2" smd rect
			(at -0.2667 0 270)
			(size 0.3048 0.381)
			(layers "B.Cu" "B.Mask" "B.Paste")
			(net "GND")
		)
	)
	(footprint ""
		(layer "B.Cu")
		(at 172.424852 -297.79976 -90)
		(property "Reference" "C1404"
			(at 0 0 90)
			(layer "B.SilkS")
			(hide yes)
			(effects
				(font
					(size 1.27 1.27)
				)
				(justify mirror)
			)
		)
		(property "Value" ""
			(at 0 0 90)
			(layer "B.Fab")
			(effects
				(font
					(size 1.27 1.27)
				)
				(justify mirror)
			)
		)
		(duplicate_pad_numbers_are_jumpers no)
		(fp_line
			(start -0.299974 0.150114)
			(end 0.299974 0.150114)
			(stroke
				(width 0.1)
				(type default)
			)
			(layer "B.Fab")
		)
		(fp_line
			(start 0.299974 0.150114)
			(end 0.299974 -0.150114)
			(stroke
				(width 0.1)
				(type default)
			)
			(layer "B.Fab")
		)
		(fp_line
			(start -0.299974 -0.150114)
			(end -0.299974 0.150114)
			(stroke
				(width 0.1)
				(type default)
			)
			(layer "B.Fab")
		)
		(fp_line
			(start 0.299974 -0.150114)
			(end -0.299974 -0.150114)
			(stroke
				(width 0.1)
				(type default)
			)
			(layer "B.Fab")
		)
		(pad "1" smd rect
			(at 0.2667 0 90)
			(size 0.3048 0.381)
			(layers "B.Cu" "B.Mask" "B.Paste")
			(net "P0V8_PEX1")
		)
		(pad "2" smd rect
			(at -0.2667 0 90)
			(size 0.3048 0.381)
			(layers "B.Cu" "B.Mask" "B.Paste")
			(net "GND")
		)
	)
)
